(kicad_pcb
	(version 20260206)
	(generator "pcbnew")
	(generator_version "10.0")
	(general
		(thickness 1.6)
		(legacy_teardrops no)
	)
	(paper "A4")
	(title_block
		(title "04192023_DAF0TMB3IC0_F0TG_MB_C_brd_V02_OCP.brd")
		(comment 1 "Grand Teton / footprints 1881-1887 of 8354")
	)
	(layers
		(0 "F.Cu" signal "TOP")
		(4 "In1.Cu" signal "GND")
		(6 "In2.Cu" signal "IN1")
		(8 "In3.Cu" signal "GND1")
		(10 "In4.Cu" signal "IN2")
		(12 "In5.Cu" signal "GND2")
		(14 "In6.Cu" signal "IN3")
		(16 "In7.Cu" signal "GND3")
		(18 "In8.Cu" signal "VCC")
		(20 "In9.Cu" signal "VCC1")
		(22 "In10.Cu" signal "GND4")
		(24 "In11.Cu" signal "IN4")
		(26 "In12.Cu" signal "GND5")
		(28 "In13.Cu" signal "IN5")
		(30 "In14.Cu" signal "GND6")
		(32 "In15.Cu" signal "IN6")
		(34 "In16.Cu" signal "GND7")
		(2 "B.Cu" signal "BOTTOM")
		(9 "F.Adhes" user "F.Adhesive")
		(11 "B.Adhes" user "B.Adhesive")
		(13 "F.Paste" user "Package Geometry/Pastemask Top")
		(15 "B.Paste" user "Package Geometry/Pastemask Bottom")
		(5 "F.SilkS" user "Ref Des/Silkscreen Top")
		(7 "B.SilkS" user "Ref Des/Silkscreen Bottom")
		(1 "F.Mask" user "Board Geometry/Soldermask Top")
		(3 "B.Mask" user "Board Geometry/Soldermask Bottom")
		(17 "Dwgs.User" user "User.Drawings")
		(19 "Cmts.User" user "User.Comments")
		(21 "Eco1.User" user "User.Eco1")
		(23 "Eco2.User" user "User.Eco2")
		(25 "Edge.Cuts" user "Board Geometry/Outline")
		(27 "Margin" user)
		(31 "F.CrtYd" user "Package Geometry/Place Bound Top")
		(29 "B.CrtYd" user "Package Geometry/Place Bound Bottom")
		(35 "F.Fab" user "Ref Des/Assembly Top")
		(33 "B.Fab" user "Ref Des/Assembly Bottom")
	)
	(footprint ""
		(layer "F.Cu")
		(at 136.10717 -153.865834 -90)
		(property "Reference" "PC346"
			(at 0 0 270)
			(layer "F.SilkS")
			(hide yes)
			(effects
				(font
					(size 1.27 1.27)
				)
			)
		)
		(property "Value" ""
			(at 0 0 270)
			(layer "F.Fab")
			(effects
				(font
					(size 1.27 1.27)
				)
			)
		)
		(duplicate_pad_numbers_are_jumpers no)
		(fp_line
			(start -0.7874 0.4064)
			(end -0.7874 -0.4064)
			(stroke
				(width 0.1524)
				(type default)
			)
			(layer "F.SilkS")
		)
		(fp_line
			(start -0.286766 0.4064)
			(end -0.7874 0.4064)
			(stroke
				(width 0.1524)
				(type default)
			)
			(layer "F.SilkS")
		)
		(fp_line
			(start 0.7874 0.4064)
			(end 0.297434 0.4064)
			(stroke
				(width 0.1524)
				(type default)
			)
			(layer "F.SilkS")
		)
		(fp_line
			(start -0.7874 -0.4064)
			(end 0.7874 -0.4064)
			(stroke
				(width 0.1524)
				(type default)
			)
			(layer "F.SilkS")
		)
		(fp_line
			(start 0.7874 -0.4064)
			(end 0.7874 0.4064)
			(stroke
				(width 0.1524)
				(type default)
			)
			(layer "F.SilkS")
		)
		(fp_line
			(start -0.67945 0.3048)
			(end -0.67945 -0.305054)
			(stroke
				(width 0.1)
				(type default)
			)
			(layer "F.Fab")
		)
		(fp_line
			(start -0.12065 0.3048)
			(end -0.67945 0.3048)
			(stroke
				(width 0.1)
				(type default)
			)
			(layer "F.Fab")
		)
		(fp_line
			(start 0.120396 0.3048)
			(end 0.120396 0.2794)
			(stroke
				(width 0.1)
				(type default)
			)
			(layer "F.Fab")
		)
		(fp_line
			(start 0.67945 0.3048)
			(end 0.120396 0.3048)
			(stroke
				(width 0.1)
				(type default)
			)
			(layer "F.Fab")
		)
		(fp_line
			(start -0.12065 0.2794)
			(end -0.12065 0.3048)
			(stroke
				(width 0.1)
				(type default)
			)
			(layer "F.Fab")
		)
		(fp_line
			(start 0.120396 0.2794)
			(end -0.12065 0.2794)
			(stroke
				(width 0.1)
				(type default)
			)
			(layer "F.Fab")
		)
		(fp_line
			(start -0.12065 -0.2794)
			(end 0.12065 -0.2794)
			(stroke
				(width 0.1)
				(type default)
			)
			(layer "F.Fab")
		)
		(fp_line
			(start 0.12065 -0.2794)
			(end 0.12065 -0.3048)
			(stroke
				(width 0.1)
				(type default)
			)
			(layer "F.Fab")
		)
		(fp_line
			(start 0.12065 -0.3048)
			(end 0.67945 -0.3048)
			(stroke
				(width 0.1)
				(type default)
			)
			(layer "F.Fab")
		)
		(fp_line
			(start 0.67945 -0.3048)
			(end 0.67945 0.3048)
			(stroke
				(width 0.1)
				(type default)
			)
			(layer "F.Fab")
		)
		(fp_line
			(start -0.67945 -0.305054)
			(end -0.12065 -0.305054)
			(stroke
				(width 0.1)
				(type default)
			)
			(layer "F.Fab")
		)
		(fp_line
			(start -0.12065 -0.305054)
			(end -0.12065 -0.2794)
			(stroke
				(width 0.1)
				(type default)
			)
			(layer "F.Fab")
		)
		(pad "1" smd circle
			(at -0.40005 0 270)
			(size 0 0)
			(layers "F.Cu" "F.Mask" "F.Paste")
			(net "PVDDCR_SOC_P1_VCC3")
		)
		(pad "2" smd circle
			(at 0.40005 0 270)
			(size 0 0)
			(layers "F.Cu" "F.Mask" "F.Paste")
			(net "GND")
		)
	)
	(footprint ""
		(layer "F.Cu")
		(at 479.38436 -107.699302 180)
		(property "Reference" "DB10"
			(at -1.716024 2.8194 0)
			(unlocked yes)
			(layer "F.SilkS")
			(effects
				(font
					(size 0.7874 0.5842)
					(thickness 0.1524)
				)
				(justify left)
			)
		)
		(property "Value" ""
			(at 0 0 180)
			(layer "F.Fab")
			(effects
				(font
					(size 1.27 1.27)
				)
			)
		)
		(duplicate_pad_numbers_are_jumpers no)
		(fp_line
			(start 3.330702 -4.771136)
			(end 0 4.011168)
			(stroke
				(width 0.1524)
				(type default)
			)
			(layer "F.SilkS")
		)
		(fp_line
			(start 0 4.011168)
			(end -3.330702 -4.771136)
			(stroke
				(width 0.1524)
				(type default)
			)
			(layer "F.SilkS")
		)
		(fp_line
			(start -3.330702 -4.771136)
			(end 3.330702 -4.771136)
			(stroke
				(width 0.1524)
				(type default)
			)
			(layer "F.SilkS")
		)
		(fp_line
			(start 3.330702 -4.771136)
			(end 0 4.011168)
			(stroke
				(width 0.1)
				(type default)
			)
			(layer "F.Fab")
		)
		(fp_line
			(start 0 4.011168)
			(end -3.330702 -4.771136)
			(stroke
				(width 0.1)
				(type default)
			)
			(layer "F.Fab")
		)
		(fp_line
			(start -3.330702 -4.771136)
			(end 3.330702 -4.771136)
			(stroke
				(width 0.1)
				(type default)
			)
			(layer "F.Fab")
		)
		(pad "1" thru_hole circle
			(at 0 0 180)
			(size 2.159 2.159)
			(drill 1.7018)
			(layers "*.Cu" "*.Mask")
			(remove_unused_layers no)
			(net "T1_GND")
			(clearance 0.0254)
			(thermal_gap 0.0254)
		)
		(pad "2" thru_hole circle
			(at -1.27 -3.348736 180)
			(size 2.159 2.159)
			(drill 1.7018)
			(layers "*.Cu" "*.Mask")
			(remove_unused_layers no)
			(net "TDR_SE_50_OHM_IN3")
			(clearance 0.0254)
			(thermal_gap 0.0254)
		)
		(pad "3" thru_hole circle
			(at 1.27 -3.348736 180)
			(size 2.159 2.159)
			(drill 1.7018)
			(layers "*.Cu" "*.Mask")
			(remove_unused_layers no)
			(net "TDR_SE_50_OHM_IN3")
			(clearance 0.0254)
			(thermal_gap 0.0254)
		)
	)
	(footprint ""
		(layer "F.Cu")
		(at 160.380934 -120.40108)
		(property "Reference" "R2227"
			(at 0 0 0)
			(layer "F.SilkS")
			(hide yes)
			(effects
				(font
					(size 1.27 1.27)
				)
			)
		)
		(property "Value" ""
			(at 0 0 0)
			(layer "F.Fab")
			(effects
				(font
					(size 1.27 1.27)
				)
			)
		)
		(duplicate_pad_numbers_are_jumpers no)
		(fp_line
			(start -0.7874 -0.4064)
			(end 0.7874 -0.4064)
			(stroke
				(width 0.1524)
				(type default)
			)
			(layer "F.SilkS")
		)
		(fp_line
			(start -0.7874 0.4064)
			(end -0.7874 -0.4064)
			(stroke
				(width 0.1524)
				(type default)
			)
			(layer "F.SilkS")
		)
		(fp_line
			(start 0.7874 -0.4064)
			(end 0.7874 0.4064)
			(stroke
				(width 0.1524)
				(type default)
			)
			(layer "F.SilkS")
		)
		(fp_line
			(start 0.7874 0.4064)
			(end -0.7874 0.4064)
			(stroke
				(width 0.1524)
				(type default)
			)
			(layer "F.SilkS")
		)
		(fp_line
			(start -0.67945 -0.305054)
			(end -0.12065 -0.305054)
			(stroke
				(width 0.1)
				(type default)
			)
			(layer "F.Fab")
		)
		(fp_line
			(start -0.67945 0.3048)
			(end -0.67945 -0.305054)
			(stroke
				(width 0.1)
				(type default)
			)
			(layer "F.Fab")
		)
		(fp_line
			(start -0.12065 -0.305054)
			(end -0.12065 -0.2794)
			(stroke
				(width 0.1)
				(type default)
			)
			(layer "F.Fab")
		)
		(fp_line
			(start -0.12065 -0.2794)
			(end 0.12065 -0.2794)
			(stroke
				(width 0.1)
				(type default)
			)
			(layer "F.Fab")
		)
		(fp_line
			(start -0.12065 0.2794)
			(end -0.12065 0.3048)
			(stroke
				(width 0.1)
				(type default)
			)
			(layer "F.Fab")
		)
		(fp_line
			(start -0.12065 0.3048)
			(end -0.67945 0.3048)
			(stroke
				(width 0.1)
				(type default)
			)
			(layer "F.Fab")
		)
		(fp_line
			(start 0.120396 0.2794)
			(end -0.12065 0.2794)
			(stroke
				(width 0.1)
				(type default)
			)
			(layer "F.Fab")
		)
		(fp_line
			(start 0.120396 0.3048)
			(end 0.120396 0.2794)
			(stroke
				(width 0.1)
				(type default)
			)
			(layer "F.Fab")
		)
		(fp_line
			(start 0.12065 -0.3048)
			(end 0.67945 -0.3048)
			(stroke
				(width 0.1)
				(type default)
			)
			(layer "F.Fab")
		)
		(fp_line
			(start 0.12065 -0.2794)
			(end 0.12065 -0.3048)
			(stroke
				(width 0.1)
				(type default)
			)
			(layer "F.Fab")
		)
		(fp_line
			(start 0.67945 -0.3048)
			(end 0.67945 0.3048)
			(stroke
				(width 0.1)
				(type default)
			)
			(layer "F.Fab")
		)
		(fp_line
			(start 0.67945 0.3048)
			(end 0.120396 0.3048)
			(stroke
				(width 0.1)
				(type default)
			)
			(layer "F.Fab")
		)
		(pad "1" smd circle
			(at -0.40005 0)
			(size 0 0)
			(layers "F.Cu" "F.Mask" "F.Paste")
			(net "A_P12V_STBY_ADR_TRIGGER")
		)
		(pad "2" smd circle
			(at 0.40005 0)
			(size 0 0)
			(layers "F.Cu" "F.Mask" "F.Paste")
			(net "GND")
		)
	)
	(footprint ""
		(layer "F.Cu")
		(at 121.909586 -408.517344 -90)
		(property "Reference" "C6697"
			(at 0 0 270)
			(layer "F.SilkS")
			(hide yes)
			(effects
				(font
					(size 1.27 1.27)
				)
			)
		)
		(property "Value" ""
			(at 0 0 270)
			(layer "F.Fab")
			(effects
				(font
					(size 1.27 1.27)
				)
			)
		)
		(duplicate_pad_numbers_are_jumpers no)
		(fp_line
			(start -0.299974 0.150114)
			(end -0.299974 -0.150114)
			(stroke
				(width 0.1)
				(type default)
			)
			(layer "F.Fab")
		)
		(fp_line
			(start 0.299974 0.150114)
			(end -0.299974 0.150114)
			(stroke
				(width 0.1)
				(type default)
			)
			(layer "F.Fab")
		)
		(fp_line
			(start -0.299974 -0.150114)
			(end 0.299974 -0.150114)
			(stroke
				(width 0.1)
				(type default)
			)
			(layer "F.Fab")
		)
		(fp_line
			(start 0.299974 -0.150114)
			(end 0.299974 0.150114)
			(stroke
				(width 0.1)
				(type default)
			)
			(layer "F.Fab")
		)
		(pad "1" smd rect
			(at -0.2667 0 270)
			(size 0.3048 0.381)
			(layers "F.Cu" "F.Mask" "F.Paste")
			(net "P5E_CPU1_P2_TX_BUF_C_DP<2>")
		)
		(pad "2" smd rect
			(at 0.2667 0 270)
			(size 0.3048 0.381)
			(layers "F.Cu" "F.Mask" "F.Paste")
			(net "P5E_CPU1_P2_TX_BUF_DP<2>")
		)
	)
	(footprint ""
		(layer "F.Cu")
		(at 59.220354 -370.57203 -90)
		(property "Reference" "C818"
			(at 0 0 270)
			(layer "F.SilkS")
			(hide yes)
			(effects
				(font
					(size 1.27 1.27)
				)
			)
		)
		(property "Value" ""
			(at 0 0 270)
			(layer "F.Fab")
			(effects
				(font
					(size 1.27 1.27)
				)
			)
		)
		(duplicate_pad_numbers_are_jumpers no)
		(fp_line
			(start -0.299974 0.150114)
			(end -0.299974 -0.150114)
			(stroke
				(width 0.1)
				(type default)
			)
			(layer "F.Fab")
		)
		(fp_line
			(start 0.299974 0.150114)
			(end -0.299974 0.150114)
			(stroke
				(width 0.1)
				(type default)
			)
			(layer "F.Fab")
		)
		(fp_line
			(start -0.299974 -0.150114)
			(end 0.299974 -0.150114)
			(stroke
				(width 0.1)
				(type default)
			)
			(layer "F.Fab")
		)
		(fp_line
			(start 0.299974 -0.150114)
			(end 0.299974 0.150114)
			(stroke
				(width 0.1)
				(type default)
			)
			(layer "F.Fab")
		)
		(pad "1" smd rect
			(at -0.2667 0 270)
			(size 0.3048 0.381)
			(layers "F.Cu" "F.Mask" "F.Paste")
			(net "P5E_CPU1_P0_TX_C_DN<9>")
		)
		(pad "2" smd rect
			(at 0.2667 0 270)
			(size 0.3048 0.381)
			(layers "F.Cu" "F.Mask" "F.Paste")
			(net "P5E_CPU1_P0_TX_DN<9>")
		)
	)
	(footprint ""
		(layer "F.Cu")
		(at 90.209878 -146.91741 180)
		(property "Reference" "R8156"
			(at 0 0 180)
			(layer "F.SilkS")
			(hide yes)
			(effects
				(font
					(size 1.27 1.27)
				)
			)
		)
		(property "Value" ""
			(at 0 0 180)
			(layer "F.Fab")
			(effects
				(font
					(size 1.27 1.27)
				)
			)
		)
		(duplicate_pad_numbers_are_jumpers no)
		(fp_line
			(start 0.7874 0.4064)
			(end -0.7874 0.4064)
			(stroke
				(width 0.1524)
				(type default)
			)
			(layer "F.SilkS")
		)
		(fp_line
			(start 0.7874 -0.4064)
			(end 0.7874 0.4064)
			(stroke
				(width 0.1524)
				(type default)
			)
			(layer "F.SilkS")
		)
		(fp_line
			(start -0.7874 0.4064)
			(end -0.7874 -0.4064)
			(stroke
				(width 0.1524)
				(type default)
			)
			(layer "F.SilkS")
		)
		(fp_line
			(start -0.7874 -0.4064)
			(end 0.7874 -0.4064)
			(stroke
				(width 0.1524)
				(type default)
			)
			(layer "F.SilkS")
		)
		(fp_line
			(start 0.67945 0.3048)
			(end 0.120396 0.3048)
			(stroke
				(width 0.1)
				(type default)
			)
			(layer "F.Fab")
		)
		(fp_line
			(start 0.67945 -0.3048)
			(end 0.67945 0.3048)
			(stroke
				(width 0.1)
				(type default)
			)
			(layer "F.Fab")
		)
		(fp_line
			(start 0.12065 -0.2794)
			(end 0.12065 -0.3048)
			(stroke
				(width 0.1)
				(type default)
			)
			(layer "F.Fab")
		)
		(fp_line
			(start 0.12065 -0.3048)
			(end 0.67945 -0.3048)
			(stroke
				(width 0.1)
				(type default)
			)
			(layer "F.Fab")
		)
		(fp_line
			(start 0.120396 0.3048)
			(end 0.120396 0.2794)
			(stroke
				(width 0.1)
				(type default)
			)
			(layer "F.Fab")
		)
		(fp_line
			(start 0.120396 0.2794)
			(end -0.12065 0.2794)
			(stroke
				(width 0.1)
				(type default)
			)
			(layer "F.Fab")
		)
		(fp_line
			(start -0.12065 0.3048)
			(end -0.67945 0.3048)
			(stroke
				(width 0.1)
				(type default)
			)
			(layer "F.Fab")
		)
		(fp_line
			(start -0.12065 0.2794)
			(end -0.12065 0.3048)
			(stroke
				(width 0.1)
				(type default)
			)
			(layer "F.Fab")
		)
		(fp_line
			(start -0.12065 -0.2794)
			(end 0.12065 -0.2794)
			(stroke
				(width 0.1)
				(type default)
			)
			(layer "F.Fab")
		)
		(fp_line
			(start -0.12065 -0.305054)
			(end -0.12065 -0.2794)
			(stroke
				(width 0.1)
				(type default)
			)
			(layer "F.Fab")
		)
		(fp_line
			(start -0.67945 0.3048)
			(end -0.67945 -0.305054)
			(stroke
				(width 0.1)
				(type default)
			)
			(layer "F.Fab")
		)
		(fp_line
			(start -0.67945 -0.305054)
			(end -0.12065 -0.305054)
			(stroke
				(width 0.1)
				(type default)
			)
			(layer "F.Fab")
		)
		(pad "1" smd circle
			(at -0.40005 0 180)
			(size 0 0)
			(layers "F.Cu" "F.Mask" "F.Paste")
			(net "PVDD18_S5_P1")
		)
		(pad "2" smd circle
			(at 0.40005 0 180)
			(size 0 0)
			(layers "F.Cu" "F.Mask" "F.Paste")
			(net "SVID_PVDDCR_CPU0_P1_SVD_R")
		)
	)
	(footprint ""
		(layer "F.Cu")
		(at 347.024706 -335.17459 -90)
		(property "Reference" "PC135_5"
			(at 0 0 270)
			(layer "F.SilkS")
			(hide yes)
			(effects
				(font
					(size 1.27 1.27)
				)
			)
		)
		(property "Value" ""
			(at 0 0 270)
			(layer "F.Fab")
			(effects
				(font
					(size 1.27 1.27)
				)
			)
		)
		(duplicate_pad_numbers_are_jumpers no)
		(fp_line
			(start -0.7874 0.4064)
			(end -0.7874 -0.4064)
			(stroke
				(width 0.1524)
				(type default)
			)
			(layer "F.SilkS")
		)
		(fp_line
			(start 0.7874 0.4064)
			(end -0.7874 0.4064)
			(stroke
				(width 0.1524)
				(type default)
			)
			(layer "F.SilkS")
		)
		(fp_line
			(start -0.7874 -0.4064)
			(end 0.7874 -0.4064)
			(stroke
				(width 0.1524)
				(type default)
			)
			(layer "F.SilkS")
		)
		(fp_line
			(start 0.7874 -0.4064)
			(end 0.7874 0.4064)
			(stroke
				(width 0.1524)
				(type default)
			)
			(layer "F.SilkS")
		)
		(fp_line
			(start -0.67945 0.3048)
			(end -0.67945 -0.305054)
			(stroke
				(width 0.1)
				(type default)
			)
			(layer "F.Fab")
		)
		(fp_line
			(start -0.12065 0.3048)
			(end -0.67945 0.3048)
			(stroke
				(width 0.1)
				(type default)
			)
			(layer "F.Fab")
		)
		(fp_line
			(start 0.120396 0.3048)
			(end 0.120396 0.2794)
			(stroke
				(width 0.1)
				(type default)
			)
			(layer "F.Fab")
		)
		(fp_line
			(start 0.67945 0.3048)
			(end 0.120396 0.3048)
			(stroke
				(width 0.1)
				(type default)
			)
			(layer "F.Fab")
		)
		(fp_line
			(start -0.12065 0.2794)
			(end -0.12065 0.3048)
			(stroke
				(width 0.1)
				(type default)
			)
			(layer "F.Fab")
		)
		(fp_line
			(start 0.120396 0.2794)
			(end -0.12065 0.2794)
			(stroke
				(width 0.1)
				(type default)
			)
			(layer "F.Fab")
		)
		(fp_line
			(start -0.12065 -0.2794)
			(end 0.12065 -0.2794)
			(stroke
				(width 0.1)
				(type default)
			)
			(layer "F.Fab")
		)
		(fp_line
			(start 0.12065 -0.2794)
			(end 0.12065 -0.3048)
			(stroke
				(width 0.1)
				(type default)
			)
			(layer "F.Fab")
		)
		(fp_line
			(start 0.12065 -0.3048)
			(end 0.67945 -0.3048)
			(stroke
				(width 0.1)
				(type default)
			)
			(layer "F.Fab")
		)
		(fp_line
			(start 0.67945 -0.3048)
			(end 0.67945 0.3048)
			(stroke
				(width 0.1)
				(type default)
			)
			(layer "F.Fab")
		)
		(fp_line
			(start -0.67945 -0.305054)
			(end -0.12065 -0.305054)
			(stroke
				(width 0.1)
				(type default)
			)
			(layer "F.Fab")
		)
		(fp_line
			(start -0.12065 -0.305054)
			(end -0.12065 -0.2794)
			(stroke
				(width 0.1)
				(type default)
			)
			(layer "F.Fab")
		)
		(pad "1" smd circle
			(at -0.40005 0 270)
			(size 0 0)
			(layers "F.Cu" "F.Mask" "F.Paste")
			(net "SW_P12V_AUX_PVDDCR_CPU1_P0_FLT")
		)
		(pad "2" smd circle
			(at 0.40005 0 270)
			(size 0 0)
			(layers "F.Cu" "F.Mask" "F.Paste")
			(net "GND")
		)
	)
)
